# S9S_MB_2U (Grand Teton) — schematic netlist excerpt (pin names and nets, part order shuffled) for the footprints in the layout excerpt that follows; sources: Cadence DE-HDL packaged netlist, KiCad conversion of 03242023_DA0F0TMBIJ0_F0T_Motherboard_J_brd_V01_OCP.brd

PC389  Q_CAP  3300PF 50V 10% X7R  pkg 0402  page 296 : A = SH_PVCCD_HV_CPU1_R ; B = VSENSE_PVCCD_HV_CPU1_DN
R2372  Q_RES  33.2 1% CHIP  pkg 0402LF  page 266 : A = SMB_VR_3V3AUX_SDA_R3 ; B = SMB_DIO_PVCCIN_CPU0
H106  HOLE  EMPTY  pkg TH  page 311 : \1\ = GND

(kicad_pcb
	(version 20260206)
	(generator "pcbnew")
	(generator_version "10.0")
	(general
		(thickness 1.6)
		(legacy_teardrops no)
	)
	(paper "A4")
	(title_block
		(title "03242023_DA0F0TMBIJ0_F0T_Motherboard_J_brd_V01_OCP.brd")
		(comment 1 "Grand Teton / footprints 3432-3434 of 6105")
	)
	(layers
		(0 "F.Cu" signal "TOP")
		(4 "In1.Cu" signal "GND")
		(6 "In2.Cu" signal "IN1")
		(8 "In3.Cu" signal "GND1")
		(10 "In4.Cu" signal "IN2")
		(12 "In5.Cu" signal "GND2")
		(14 "In6.Cu" signal "IN3")
		(16 "In7.Cu" signal "GND3")
		(18 "In8.Cu" signal "VCC")
		(20 "In9.Cu" signal "VCC1")
		(22 "In10.Cu" signal "GND4")
		(24 "In11.Cu" signal "IN4")
		(26 "In12.Cu" signal "GND5")
		(28 "In13.Cu" signal "IN5")
		(30 "In14.Cu" signal "GND6")
		(32 "In15.Cu" signal "IN6")
		(34 "In16.Cu" signal "GND7")
		(2 "B.Cu" signal "BOTTOM")
		(9 "F.Adhes" user "F.Adhesive")
		(11 "B.Adhes" user "B.Adhesive")
		(13 "F.Paste" user "Package Geometry/Pastemask Top")
		(15 "B.Paste" user "Package Geometry/Pastemask Bottom")
		(5 "F.SilkS" user "Ref Des/Silkscreen Top")
		(7 "B.SilkS" user "Ref Des/Silkscreen Bottom")
		(1 "F.Mask" user "Board Geometry/Soldermask Top")
		(3 "B.Mask" user "Board Geometry/Soldermask Bottom")
		(17 "Dwgs.User" user "User.Drawings")
		(19 "Cmts.User" user "User.Comments")
		(21 "Eco1.User" user "User.Eco1")
		(23 "Eco2.User" user "User.Eco2")
		(25 "Edge.Cuts" user "Board Geometry/Outline")
		(27 "Margin" user)
		(31 "F.CrtYd" user "Package Geometry/Place Bound Top")
		(29 "B.CrtYd" user "Package Geometry/Place Bound Bottom")
		(35 "F.Fab" user "Ref Des/Assembly Top")
		(33 "B.Fab" user "Ref Des/Assembly Bottom")
	)
	(footprint ""
		(layer "F.Cu")
		(at 351.97288 -363.692948 -90)
		(property "Reference" "R2372"
			(at 0 0 270)
			(layer "F.SilkS")
			(hide yes)
			(effects
				(font
					(size 1.27 1.27)
				)
			)
		)
		(property "Value" ""
			(at 0 0 270)
			(layer "F.Fab")
			(effects
				(font
					(size 1.27 1.27)
				)
			)
		)
		(duplicate_pad_numbers_are_jumpers no)
		(fp_line
			(start -0.7874 0.4064)
			(end -0.7874 -0.4064)
			(stroke
				(width 0.1524)
				(type default)
			)
			(layer "F.SilkS")
		)
		(fp_line
			(start 0.7874 0.4064)
			(end -0.7874 0.4064)
			(stroke
				(width 0.1524)
				(type default)
			)
			(layer "F.SilkS")
		)
		(fp_line
			(start -0.7874 -0.4064)
			(end 0.7874 -0.4064)
			(stroke
				(width 0.1524)
				(type default)
			)
			(layer "F.SilkS")
		)
		(fp_line
			(start 0.7874 -0.4064)
			(end 0.7874 0.4064)
			(stroke
				(width 0.1524)
				(type default)
			)
			(layer "F.SilkS")
		)
		(fp_line
			(start -0.67945 0.3048)
			(end -0.67945 -0.305054)
			(stroke
				(width 0.1)
				(type default)
			)
			(layer "F.Fab")
		)
		(fp_line
			(start -0.12065 0.3048)
			(end -0.67945 0.3048)
			(stroke
				(width 0.1)
				(type default)
			)
			(layer "F.Fab")
		)
		(fp_line
			(start 0.120396 0.3048)
			(end 0.120396 0.2794)
			(stroke
				(width 0.1)
				(type default)
			)
			(layer "F.Fab")
		)
		(fp_line
			(start 0.67945 0.3048)
			(end 0.120396 0.3048)
			(stroke
				(width 0.1)
				(type default)
			)
			(layer "F.Fab")
		)
		(fp_line
			(start -0.12065 0.2794)
			(end -0.12065 0.3048)
			(stroke
				(width 0.1)
				(type default)
			)
			(layer "F.Fab")
		)
		(fp_line
			(start 0.120396 0.2794)
			(end -0.12065 0.2794)
			(stroke
				(width 0.1)
				(type default)
			)
			(layer "F.Fab")
		)
		(fp_line
			(start -0.12065 -0.2794)
			(end 0.12065 -0.2794)
			(stroke
				(width 0.1)
				(type default)
			)
			(layer "F.Fab")
		)
		(fp_line
			(start 0.12065 -0.2794)
			(end 0.12065 -0.3048)
			(stroke
				(width 0.1)
				(type default)
			)
			(layer "F.Fab")
		)
		(fp_line
			(start 0.12065 -0.3048)
			(end 0.67945 -0.3048)
			(stroke
				(width 0.1)
				(type default)
			)
			(layer "F.Fab")
		)
		(fp_line
			(start 0.67945 -0.3048)
			(end 0.67945 0.3048)
			(stroke
				(width 0.1)
				(type default)
			)
			(layer "F.Fab")
		)
		(fp_line
			(start -0.67945 -0.305054)
			(end -0.12065 -0.305054)
			(stroke
				(width 0.1)
				(type default)
			)
			(layer "F.Fab")
		)
		(fp_line
			(start -0.12065 -0.305054)
			(end -0.12065 -0.2794)
			(stroke
				(width 0.1)
				(type default)
			)
			(layer "F.Fab")
		)
		(pad "1" smd circle
			(at -0.40005 0 270)
			(size 0 0)
			(layers "F.Cu" "F.Mask" "F.Paste")
			(net "SMB_VR_3V3AUX_SDA_R3")
		)
		(pad "2" smd circle
			(at 0.40005 0 270)
			(size 0 0)
			(layers "F.Cu" "F.Mask" "F.Paste")
			(net "SMB_DIO_PVCCIN_CPU0")
		)
	)
	(footprint ""
		(layer "F.Cu")
		(at 22.991572 -162.20567 -90)
		(property "Reference" "PC389"
			(at 0 0 270)
			(layer "F.SilkS")
			(hide yes)
			(effects
				(font
					(size 1.27 1.27)
				)
			)
		)
		(property "Value" ""
			(at 0 0 270)
			(layer "F.Fab")
			(effects
				(font
					(size 1.27 1.27)
				)
			)
		)
		(duplicate_pad_numbers_are_jumpers no)
		(fp_line
			(start -0.7874 0.4064)
			(end -0.7874 -0.4064)
			(stroke
				(width 0.1524)
				(type default)
			)
			(layer "F.SilkS")
		)
		(fp_line
			(start 0.7874 0.4064)
			(end -0.7874 0.4064)
			(stroke
				(width 0.1524)
				(type default)
			)
			(layer "F.SilkS")
		)
		(fp_line
			(start -0.7874 -0.4064)
			(end 0.7874 -0.4064)
			(stroke
				(width 0.1524)
				(type default)
			)
			(layer "F.SilkS")
		)
		(fp_line
			(start 0.7874 -0.4064)
			(end 0.7874 0.4064)
			(stroke
				(width 0.1524)
				(type default)
			)
			(layer "F.SilkS")
		)
		(fp_line
			(start -0.67945 0.3048)
			(end -0.67945 -0.305054)
			(stroke
				(width 0.1)
				(type default)
			)
			(layer "F.Fab")
		)
		(fp_line
			(start -0.12065 0.3048)
			(end -0.67945 0.3048)
			(stroke
				(width 0.1)
				(type default)
			)
			(layer "F.Fab")
		)
		(fp_line
			(start 0.120396 0.3048)
			(end 0.120396 0.2794)
			(stroke
				(width 0.1)
				(type default)
			)
			(layer "F.Fab")
		)
		(fp_line
			(start 0.67945 0.3048)
			(end 0.120396 0.3048)
			(stroke
				(width 0.1)
				(type default)
			)
			(layer "F.Fab")
		)
		(fp_line
			(start -0.12065 0.2794)
			(end -0.12065 0.3048)
			(stroke
				(width 0.1)
				(type default)
			)
			(layer "F.Fab")
		)
		(fp_line
			(start 0.120396 0.2794)
			(end -0.12065 0.2794)
			(stroke
				(width 0.1)
				(type default)
			)
			(layer "F.Fab")
		)
		(fp_line
			(start -0.12065 -0.2794)
			(end 0.12065 -0.2794)
			(stroke
				(width 0.1)
				(type default)
			)
			(layer "F.Fab")
		)
		(fp_line
			(start 0.12065 -0.2794)
			(end 0.12065 -0.3048)
			(stroke
				(width 0.1)
				(type default)
			)
			(layer "F.Fab")
		)
		(fp_line
			(start 0.12065 -0.3048)
			(end 0.67945 -0.3048)
			(stroke
				(width 0.1)
				(type default)
			)
			(layer "F.Fab")
		)
		(fp_line
			(start 0.67945 -0.3048)
			(end 0.67945 0.3048)
			(stroke
				(width 0.1)
				(type default)
			)
			(layer "F.Fab")
		)
		(fp_line
			(start -0.67945 -0.305054)
			(end -0.12065 -0.305054)
			(stroke
				(width 0.1)
				(type default)
			)
			(layer "F.Fab")
		)
		(fp_line
			(start -0.12065 -0.305054)
			(end -0.12065 -0.2794)
			(stroke
				(width 0.1)
				(type default)
			)
			(layer "F.Fab")
		)
		(pad "1" smd circle
			(at -0.40005 0 270)
			(size 0 0)
			(layers "F.Cu" "F.Mask" "F.Paste")
			(net "SH_PVCCD_HV_CPU1_R")
		)
		(pad "2" smd circle
			(at 0.40005 0 270)
			(size 0 0)
			(layers "F.Cu" "F.Mask" "F.Paste")
			(net "VSENSE_PVCCD_HV_CPU1_DN")
		)
	)
	(footprint ""
		(layer "F.Cu")
		(at 464.799934 -22.29993)
		(property "Reference" "H106"
			(at -6.743954 -4.50088 0)
			(unlocked yes)
			(layer "F.SilkS")
			(effects
				(font
					(size 0.7874 0.5842)
					(thickness 0.1524)
				)
				(justify left)
			)
		)
		(property "Value" ""
			(at 0 0 0)
			(layer "F.Fab")
			(effects
				(font
					(size 1.27 1.27)
				)
			)
		)
		(duplicate_pad_numbers_are_jumpers no)
		(pad "1" thru_hole circle
			(at 0 0)
			(size 10.0076 10.0076)
			(drill 5.6134)
			(layers "*.Cu" "*.Mask")
			(remove_unused_layers no)
			(net "GND")
			(clearance -1.9431)
		)
	)
)
